# Wiwynn_Honey Badger_BaseBoard_8L_Stackup_20150121.xlsx — Wiwynn (pcb-stackup)
|  |  |  |  |  |  |  |  |  |  | Single Ended Type(mil) |  |  |  |  | Differential Type(mil) |  |  |  |  |  |  |  |  |  |  |  |
|  |  |  |  |  |  |  |  |  | Imp | 50 |  |  |  | Imp | 85 |  |  |  |  |  | 100 |  |  |  |  |  |
|  |  |  |  |  |  |  |  |  | Variation | Inner /Outer ±5Ω |  |  |  | Variation | Inner 10% / Outer 10% |  |  |  |  |  | Inner 10% / Outer 10% |  |  |  |  |  |
|  |  |  |  |  |  |  |  |  | Bus | MISC |  |  |  | Bus | PCIe / USB / SATA / SGMII |  |  |  |  |  | SAS (PMC or LSI) / SGMII |  |  |  |  |  |
|  |  |  |  |  |  |  |  |  | Type | SE |  |  |  | Type | DP |  |  |  |  |  | DP |  |  |  |  |  |
| Layer |  |  | Thickness |  | Glass style | Er |  | Df(1G) | Layers | All |  |  |  | Layers | All |  |  |  |  |  | All |  |  |  |  |  |
|  |  | Cu oz | Wiwynn | Vender |  | Wiwynn | Vender |  |  | Wiwynn |  | Vender |  |  | Wiwynn |  |  | Vender |  |  | Wiwynn |  |  | Vender |  |  |
|  | Mask |  | 0.5 |  |  | 3.8 |  |  |  | Width | Imp | Width | Imp |  | Width | Space | Imp | Width | Space | Imp | Width | Space | Imp | Width | Space | Imp |
| Top | Signal | 0.5 oz + plating | 1.9 |  |  |  |  |  | S1 | 4.5 |  |  |  | S1 | 5.5 | 8 |  |  |  |  | 4 | 9.5 |  |  |  |  |
|  | Prepreg |  | 2.7 |  |  | 4 |  |  |  |  |  |  |  |  |  |  |  |  |  |  |  |  |  |  |  |  |
| L2 | GND | 1oz | 1.3 |  |  |  |  |  | G2 | Reference layer |  | Reference layer |  | G2 | Reference layer |  |  | Reference layer |  |  | Reference layer |  |  | Reference layer |  |  |
|  | Core |  | 4 |  |  | 4 |  |  |  |  |  |  |  |  |  |  |  |  |  |  |  |  |  |  |  |  |
| L3 | Signal | 1 oz | 1.3 |  |  |  |  |  | S3 | 5 |  |  |  | S3 | 5 | 6 |  |  |  |  | 4 | 9 |  |  |  |  |
|  | Prepreg |  | 17 |  |  | 4.5 |  |  |  |  |  |  |  |  |  |  |  |  |  |  |  |  |  |  |  |  |
| L4 | PWR | 1 | 1.3 |  |  |  |  |  | P4 | Reference layer |  | Reference layer |  | P4 | Reference layer |  |  | Reference layer |  |  | Reference layer |  |  | Reference layer |  |  |
|  | Core |  | 3 |  |  | 4 |  |  |  |  |  |  |  |  |  |  |  |  |  |  |  |  |  |  |  |  |
| L5 | PWR | 1 | 1.3 |  |  |  |  |  | P5 | Reference layer |  | Reference layer |  | P5 | Reference layer |  |  | Reference layer |  |  | Reference layer |  |  | Reference layer |  |  |
|  | Prepreg |  | 17 |  |  | 4.5 |  |  |  |  |  |  |  |  |  |  |  |  |  |  |  |  |  |  |  |  |
| L6 | Signal | 1 oz | 1.3 |  |  |  |  |  | S6 | 5 |  |  |  | S6 | 5 | 6 |  |  |  |  | 4 | 9 |  |  |  |  |
|  | Core |  | 4 |  |  | 4 |  |  |  |  |  |  |  |  |  |  |  |  |  |  |  |  |  |  |  |  |
| L7 | GND | 1oz | 1.3 |  |  |  |  |  | G7 | Reference layer |  | Reference layer |  | G7 | Reference layer |  |  | Reference layer |  |  | Reference layer |  |  | Reference layer |  |  |
|  | Prepreg |  | 2.7 |  |  | 4 |  |  |  |  |  |  |  |  |  |  |  |  |  |  |  |  |  |  |  |  |
| Bottom | Signal | 0.5 oz + plating | 1.9 |  |  |  |  |  | S8 | 4.5 |  |  |  | S8 | 5.5 | 8 |  |  |  |  | 4 | 9.5 |  |  |  |  |
|  | Mask |  | 0.5 |  |  | 3.8 |  |  |  |  |  |  |  |  |  |  |  |  |  |  |  |  |  |  |  |  |
| Thickness requirement: 1.6±10% mm |  | mil | 62.999999999999993 |  | +/-10% |  |  |  |  |  |  |  |  |  |  |  |  |  |  |  |  |  |  |  |  |  |
|  |  | mm | 1.6002032004064006 |  |  |  |  |  |  |  |  |  |  |  |  |  |  |  |  |  |  |  |  |  |  |  |
